(kicad_pcb
	(version 20241229)
	(generator "pcbnew")
	(generator_version "9.0")
	(general
		(thickness 1.711)
		(legacy_teardrops no)
	)
	(paper "A4")
	(title_block
		(title "Antmicro Baseboard for Jetson AGX Thor")
		(date "2026-02-18")
		(rev "1.1.0")
		(company "Antmicro Ltd")
		(comment 1 "www.antmicro.com")
		(comment 9 "footprints 943-946 of 1170")
	)
	(layers
		(0 "F.Cu" signal)
		(4 "In1.Cu" signal)
		(6 "In2.Cu" signal)
		(8 "In3.Cu" signal)
		(10 "In4.Cu" jumper)
		(12 "In5.Cu" signal)
		(14 "In6.Cu" signal)
		(16 "In7.Cu" signal)
		(18 "In8.Cu" signal)
		(2 "B.Cu" signal)
		(9 "F.Adhes" user "F.Adhesive")
		(11 "B.Adhes" user "B.Adhesive")
		(13 "F.Paste" user)
		(15 "B.Paste" user)
		(5 "F.SilkS" user "F.Silkscreen")
		(7 "B.SilkS" user "B.Silkscreen")
		(1 "F.Mask" user)
		(3 "B.Mask" user)
		(17 "Dwgs.User" user "User.Drawings")
		(19 "Cmts.User" user "User.Comments")
		(21 "Eco1.User" user "User.Eco1")
		(23 "Eco2.User" user "User.Eco2")
		(25 "Edge.Cuts" user)
		(27 "Margin" user)
		(31 "F.CrtYd" user "F.Courtyard")
		(29 "B.CrtYd" user "B.Courtyard")
		(35 "F.Fab" user)
		(33 "B.Fab" user)
	)
	(footprint "antmicro-footprints:C_0402_1005Metric"
		(layer "B.Cu")
		(at 134.8 65.2 -90)
		(descr "Capacitor SMD 0402")
		(tags "capacitor SMD 0402")
		(property "Reference" "C208"
			(at 0.9 -0.4 90)
			(layer "B.SilkS")
			(effects
				(font
					(size 0.7 0.7)
					(thickness 0.15)
				)
				(justify left bottom mirror)
			)
		)
		(property "Value" "C_100n_0402"
			(at -1.022927 -2.155213 90)
			(layer "B.Fab")
			(effects
				(font
					(size 0.7 0.7)
					(thickness 0.15)
				)
				(justify left bottom mirror)
			)
		)
		(property "Datasheet" "https://www.murata.com/products/productdetail?partno=GRM155R61H104KE14%23"
			(at 0 0 90)
			(layer "B.Fab")
			(hide yes)
			(effects
				(font
					(size 1.27 1.27)
					(thickness 0.15)
				)
				(justify mirror)
			)
		)
		(property "Description" "SMD Multilayer Ceramic Capacitor, 0.1 µF, 50 V, 0402 [1005 Metric], ± 10%, X5R, GRM Series"
			(at 0 0 90)
			(layer "B.Fab")
			(hide yes)
			(effects
				(font
					(size 1.27 1.27)
					(thickness 0.15)
				)
				(justify mirror)
			)
		)
		(property "Manufacturer" "Murata"
			(at 0 0 90)
			(unlocked yes)
			(layer "B.Fab")
			(hide yes)
			(effects
				(font
					(size 1 1)
					(thickness 0.15)
				)
				(justify mirror)
			)
		)
		(property "MPN" "GRM155R61H104KE14D"
			(at 0 0 90)
			(unlocked yes)
			(layer "B.Fab")
			(hide yes)
			(effects
				(font
					(size 1 1)
					(thickness 0.15)
				)
				(justify mirror)
			)
		)
		(property "Val" "100n"
			(at 0 0 90)
			(unlocked yes)
			(layer "B.Fab")
			(hide yes)
			(effects
				(font
					(size 1 1)
					(thickness 0.15)
				)
				(justify mirror)
			)
		)
		(property "License" "Apache-2.0"
			(at 0 0 90)
			(unlocked yes)
			(layer "B.Fab")
			(hide yes)
			(effects
				(font
					(size 1 1)
					(thickness 0.15)
				)
				(justify mirror)
			)
		)
		(property "Author" "Antmicro"
			(at 0 0 90)
			(unlocked yes)
			(layer "B.Fab")
			(hide yes)
			(effects
				(font
					(size 1 1)
					(thickness 0.15)
				)
				(justify mirror)
			)
		)
		(property "Voltage" "50V"
			(at 0 0 90)
			(unlocked yes)
			(layer "B.Fab")
			(hide yes)
			(effects
				(font
					(size 1 1)
					(thickness 0.15)
				)
				(justify mirror)
			)
		)
		(property "Dielectric" "X5R"
			(at 0 0 90)
			(unlocked yes)
			(layer "B.Fab")
			(hide yes)
			(effects
				(font
					(size 1 1)
					(thickness 0.15)
				)
				(justify mirror)
			)
		)
		(sheetname "/Peripherals/")
		(sheetfile "peripherals.kicad_sch")
		(attr smd)
		(fp_poly
			(pts
				(xy -0.925 0.47) (xy 0.925 0.47) (xy 0.925 -0.47) (xy -0.925 -0.47)
			)
			(stroke
				(width 0.05)
				(type default)
			)
			(fill no)
			(layer "B.CrtYd")
		)
		(fp_line
			(start -0.494 0.25)
			(end 0.504 0.25)
			(stroke
				(width 0.15)
				(type solid)
			)
			(layer "B.Fab")
		)
		(fp_line
			(start 0.504 0.25)
			(end 0.504 -0.248)
			(stroke
				(width 0.15)
				(type solid)
			)
			(layer "B.Fab")
		)
		(fp_line
			(start -0.494 -0.248)
			(end -0.494 0.25)
			(stroke
				(width 0.15)
				(type solid)
			)
			(layer "B.Fab")
		)
		(fp_line
			(start 0.504 -0.248)
			(end -0.494 -0.248)
			(stroke
				(width 0.15)
				(type solid)
			)
			(layer "B.Fab")
		)
		(fp_text user "Author: Antmicro"
			(at -0.939 -3.399 90)
			(layer "B.Fab")
			(effects
				(font
					(size 0.7 0.7)
					(thickness 0.15)
				)
				(justify left bottom mirror)
			)
		)
		(fp_text user "License: Apache-2.0"
			(at -0.939 -5.799 90)
			(layer "B.Fab")
			(effects
				(font
					(size 0.7 0.7)
					(thickness 0.15)
				)
				(justify left bottom mirror)
			)
		)
		(fp_text user "${REFERENCE}"
			(at -0.939 -4.599 90)
			(layer "B.Fab")
			(effects
				(font
					(size 0.7 0.7)
					(thickness 0.15)
				)
				(justify left bottom mirror)
			)
		)
		(pad "1" smd roundrect
			(at -0.48 0 270)
			(size 0.59 0.64)
			(layers "B.Cu" "B.Mask" "B.Paste")
			(roundrect_rratio 0.25)
			(net 2 "+3V3")
			(pintype "passive")
		)
		(pad "2" smd roundrect
			(at 0.48 0 270)
			(size 0.59 0.64)
			(layers "B.Cu" "B.Mask" "B.Paste")
			(roundrect_rratio 0.25)
			(net 1 "GND")
			(pintype "passive")
		)
	)
	(footprint "antmicro-footprints:R_0402_1005Metric"
		(layer "B.Cu")
		(at 64.2 66.52 -90)
		(descr "Resistor SMD 0402")
		(tags "resistor SMD 0402")
		(property "Reference" "R389"
			(at -9.7 0 90)
			(layer "B.SilkS")
			(effects
				(font
					(size 0.7 0.7)
					(thickness 0.15)
				)
				(justify left bottom mirror)
			)
		)
		(property "Value" "R_2k2_0402"
			(at -1.011843 -1.772047 90)
			(layer "B.Fab")
			(effects
				(font
					(size 0.7 0.7)
					(thickness 0.15)
				)
				(justify left bottom mirror)
			)
		)
		(property "Datasheet" "https://www.bourns.com/docs/product-datasheets/cr.pdf"
			(at 0 0 90)
			(layer "B.Fab")
			(hide yes)
			(effects
				(font
					(size 1.27 1.27)
					(thickness 0.15)
				)
				(justify mirror)
			)
		)
		(property "Description" "SMD Chip Resistor, 2.2 kohm, ± 1%, 62.5 mW, 0402 [1005 Metric], Thick Film, General Purpose"
			(at 0 0 90)
			(layer "B.Fab")
			(hide yes)
			(effects
				(font
					(size 1.27 1.27)
					(thickness 0.15)
				)
				(justify mirror)
			)
		)
		(property "MPN" "CR0402-FX-2201GLF"
			(at 0 0 90)
			(unlocked yes)
			(layer "B.Fab")
			(hide yes)
			(effects
				(font
					(size 1 1)
					(thickness 0.15)
				)
				(justify mirror)
			)
		)
		(property "Manufacturer" "Bourns"
			(at 0 0 90)
			(unlocked yes)
			(layer "B.Fab")
			(hide yes)
			(effects
				(font
					(size 1 1)
					(thickness 0.15)
				)
				(justify mirror)
			)
		)
		(property "License" "Apache-2.0"
			(at 0 0 90)
			(unlocked yes)
			(layer "B.Fab")
			(hide yes)
			(effects
				(font
					(size 1 1)
					(thickness 0.15)
				)
				(justify mirror)
			)
		)
		(property "Author" "Antmicro"
			(at 0 0 90)
			(unlocked yes)
			(layer "B.Fab")
			(hide yes)
			(effects
				(font
					(size 1 1)
					(thickness 0.15)
				)
				(justify mirror)
			)
		)
		(property "Val" "2k2"
			(at 0 0 90)
			(unlocked yes)
			(layer "B.Fab")
			(hide yes)
			(effects
				(font
					(size 1 1)
					(thickness 0.15)
				)
				(justify mirror)
			)
		)
		(property "Tolerance" "1%"
			(at 0 0 90)
			(unlocked yes)
			(layer "B.Fab")
			(hide yes)
			(effects
				(font
					(size 1 1)
					(thickness 0.15)
				)
				(justify mirror)
			)
		)
		(sheetname "/CSI/")
		(sheetfile "csi.kicad_sch")
		(attr smd)
		(fp_rect
			(start -0.925 0.47)
			(end 0.925 -0.47)
			(stroke
				(width 0.05)
				(type default)
			)
			(fill no)
			(layer "B.CrtYd")
		)
		(fp_rect
			(start -0.5 0.25)
			(end 0.5 -0.25)
			(stroke
				(width 0.15)
				(type solid)
			)
			(fill no)
			(layer "B.Fab")
		)
		(fp_text user "${REFERENCE}"
			(at -0.95 -3.168 90)
			(layer "B.Fab")
			(effects
				(font
					(size 0.7 0.7)
					(thickness 0.15)
				)
				(justify left bottom mirror)
			)
		)
		(fp_text user "Author: Antmicro"
			(at -0.95 -4.169 90)
			(layer "B.Fab")
			(effects
				(font
					(size 0.7 0.7)
					(thickness 0.15)
				)
				(justify left bottom mirror)
			)
		)
		(fp_text user "License: Apache-2.0"
			(at -0.95 -5.169 90)
			(layer "B.Fab")
			(effects
				(font
					(size 0.7 0.7)
					(thickness 0.15)
				)
				(justify left bottom mirror)
			)
		)
		(pad "1" smd roundrect
			(at -0.48 0 270)
			(size 0.59 0.64)
			(layers "B.Cu" "B.Mask" "B.Paste")
			(roundrect_rratio 0.25)
			(net 979 "/CSI/CSIA_I2C_VCC")
			(pintype "passive")
		)
		(pad "2" smd roundrect
			(at 0.48 0 270)
			(size 0.59 0.64)
			(layers "B.Cu" "B.Mask" "B.Paste")
			(roundrect_rratio 0.25)
			(net 988 "/CSI/SCL_CAM1")
			(pintype "passive")
		)
	)
	(footprint "antmicro-footprints:C_0402_1005Metric"
		(layer "B.Cu")
		(at 95.180001 103.6 -90)
		(descr "Capacitor SMD 0402")
		(tags "capacitor SMD 0402")
		(property "Reference" "C326"
			(at -3.8 -0.3 90)
			(layer "B.SilkS")
			(effects
				(font
					(size 0.7 0.7)
					(thickness 0.15)
				)
				(justify left bottom mirror)
			)
		)
		(property "Value" "C_100n_0402"
			(at -1.022927 -2.155213 90)
			(layer "B.Fab")
			(effects
				(font
					(size 0.7 0.7)
					(thickness 0.15)
				)
				(justify left bottom mirror)
			)
		)
		(property "Datasheet" "https://www.murata.com/products/productdetail?partno=GRM155R61H104KE14%23"
			(at 0 0 90)
			(layer "B.Fab")
			(hide yes)
			(effects
				(font
					(size 1.27 1.27)
					(thickness 0.15)
				)
				(justify mirror)
			)
		)
		(property "Description" "SMD Multilayer Ceramic Capacitor, 0.1 µF, 50 V, 0402 [1005 Metric], ± 10%, X5R, GRM Series"
			(at 0 0 90)
			(layer "B.Fab")
			(hide yes)
			(effects
				(font
					(size 1.27 1.27)
					(thickness 0.15)
				)
				(justify mirror)
			)
		)
		(property "Manufacturer" "Murata"
			(at 0 0 90)
			(unlocked yes)
			(layer "B.Fab")
			(hide yes)
			(effects
				(font
					(size 1 1)
					(thickness 0.15)
				)
				(justify mirror)
			)
		)
		(property "MPN" "GRM155R61H104KE14D"
			(at 0 0 90)
			(unlocked yes)
			(layer "B.Fab")
			(hide yes)
			(effects
				(font
					(size 1 1)
					(thickness 0.15)
				)
				(justify mirror)
			)
		)
		(property "Val" "100n"
			(at 0 0 90)
			(unlocked yes)
			(layer "B.Fab")
			(hide yes)
			(effects
				(font
					(size 1 1)
					(thickness 0.15)
				)
				(justify mirror)
			)
		)
		(property "License" "Apache-2.0"
			(at 0 0 90)
			(unlocked yes)
			(layer "B.Fab")
			(hide yes)
			(effects
				(font
					(size 1 1)
					(thickness 0.15)
				)
				(justify mirror)
			)
		)
		(property "Author" "Antmicro"
			(at 0 0 90)
			(unlocked yes)
			(layer "B.Fab")
			(hide yes)
			(effects
				(font
					(size 1 1)
					(thickness 0.15)
				)
				(justify mirror)
			)
		)
		(property "Voltage" "50V"
			(at 0 0 90)
			(unlocked yes)
			(layer "B.Fab")
			(hide yes)
			(effects
				(font
					(size 1 1)
					(thickness 0.15)
				)
				(justify mirror)
			)
		)
		(property "Dielectric" "X5R"
			(at 0 0 90)
			(unlocked yes)
			(layer "B.Fab")
			(hide yes)
			(effects
				(font
					(size 1 1)
					(thickness 0.15)
				)
				(justify mirror)
			)
		)
		(sheetname "/SoM_IO2/")
		(sheetfile "som_io2.kicad_sch")
		(attr smd)
		(fp_poly
			(pts
				(xy -0.925 0.47) (xy 0.925 0.47) (xy 0.925 -0.47) (xy -0.925 -0.47)
			)
			(stroke
				(width 0.05)
				(type default)
			)
			(fill no)
			(layer "B.CrtYd")
		)
		(fp_line
			(start -0.494 0.25)
			(end 0.504 0.25)
			(stroke
				(width 0.15)
				(type solid)
			)
			(layer "B.Fab")
		)
		(fp_line
			(start 0.504 0.25)
			(end 0.504 -0.248)
			(stroke
				(width 0.15)
				(type solid)
			)
			(layer "B.Fab")
		)
		(fp_line
			(start -0.494 -0.248)
			(end -0.494 0.25)
			(stroke
				(width 0.15)
				(type solid)
			)
			(layer "B.Fab")
		)
		(fp_line
			(start 0.504 -0.248)
			(end -0.494 -0.248)
			(stroke
				(width 0.15)
				(type solid)
			)
			(layer "B.Fab")
		)
		(fp_text user "${REFERENCE}"
			(at -0.939 -4.599 90)
			(layer "B.Fab")
			(effects
				(font
					(size 0.7 0.7)
					(thickness 0.15)
				)
				(justify left bottom mirror)
			)
		)
		(fp_text user "License: Apache-2.0"
			(at -0.939 -5.799 90)
			(layer "B.Fab")
			(effects
				(font
					(size 0.7 0.7)
					(thickness 0.15)
				)
				(justify left bottom mirror)
			)
		)
		(fp_text user "Author: Antmicro"
			(at -0.939 -3.399 90)
			(layer "B.Fab")
			(effects
				(font
					(size 0.7 0.7)
					(thickness 0.15)
				)
				(justify left bottom mirror)
			)
		)
		(pad "1" smd roundrect
			(at -0.48 0 270)
			(size 0.59 0.64)
			(layers "B.Cu" "B.Mask" "B.Paste")
			(roundrect_rratio 0.25)
			(net 570 "/Expansion connector/DP1.TX2+")
			(pintype "passive")
		)
		(pad "2" smd roundrect
			(at 0.48 0 270)
			(size 0.59 0.64)
			(layers "B.Cu" "B.Mask" "B.Paste")
			(roundrect_rratio 0.25)
			(net 1223 "/SoM_IO2/DP1.TX2_C+")
			(pintype "passive")
		)
	)
	(footprint "antmicro-footprints:C_0402_1005Metric"
		(layer "B.Cu")
		(at 180.23 82.5)
		(descr "Capacitor SMD 0402")
		(tags "capacitor SMD 0402")
		(property "Reference" "C262"
			(at -1.83 0.5 0)
			(layer "B.SilkS")
			(effects
				(font
					(size 0.7 0.7)
					(thickness 0.15)
				)
				(justify right top mirror)
			)
		)
		(property "Value" "C_1u_25V_0402"
			(at -1.022927 -2.155213 0)
			(layer "B.Fab")
			(effects
				(font
					(size 0.7 0.7)
					(thickness 0.15)
				)
				(justify right top mirror)
			)
		)
		(property "Datasheet" "https://www.murata.com/products/productdetail?partno=GRM155R61E105KE11%23"
			(at 0 0 0)
			(layer "B.Fab")
			(hide yes)
			(effects
				(font
					(size 1.27 1.27)
					(thickness 0.15)
				)
				(justify mirror)
			)
		)
		(property "Description" "SMD Multilayer Ceramic Capacitor, 1 µF, 25 V, 0402 [1005 Metric], ± 10%, X5R, GRM Series"
			(at 0 0 0)
			(layer "B.Fab")
			(hide yes)
			(effects
				(font
					(size 1.27 1.27)
					(thickness 0.15)
				)
				(justify mirror)
			)
		)
		(property "MPN" "GRM155R61E105KE11J"
			(at 0 0 180)
			(unlocked yes)
			(layer "B.Fab")
			(hide yes)
			(effects
				(font
					(size 1 1)
					(thickness 0.15)
				)
				(justify mirror)
			)
		)
		(property "Manufacturer" "Murata"
			(at 0 0 180)
			(unlocked yes)
			(layer "B.Fab")
			(hide yes)
			(effects
				(font
					(size 1 1)
					(thickness 0.15)
				)
				(justify mirror)
			)
		)
		(property "License" "Apache-2.0"
			(at 0 0 180)
			(unlocked yes)
			(layer "B.Fab")
			(hide yes)
			(effects
				(font
					(size 1 1)
					(thickness 0.15)
				)
				(justify mirror)
			)
		)
		(property "Author" "Antmicro"
			(at 0 0 180)
			(unlocked yes)
			(layer "B.Fab")
			(hide yes)
			(effects
				(font
					(size 1 1)
					(thickness 0.15)
				)
				(justify mirror)
			)
		)
		(property "Val" "1u"
			(at 0 0 180)
			(unlocked yes)
			(layer "B.Fab")
			(hide yes)
			(effects
				(font
					(size 1 1)
					(thickness 0.15)
				)
				(justify mirror)
			)
		)
		(property "Voltage" "25V"
			(at 0 0 180)
			(unlocked yes)
			(layer "B.Fab")
			(hide yes)
			(effects
				(font
					(size 1 1)
					(thickness 0.15)
				)
				(justify mirror)
			)
		)
		(property "Dielectric" "X5R"
			(at 0 0 180)
			(unlocked yes)
			(layer "B.Fab")
			(hide yes)
			(effects
				(font
					(size 1 1)
					(thickness 0.15)
				)
				(justify mirror)
			)
		)
		(sheetname "/Power/")
		(sheetfile "power.kicad_sch")
		(attr smd exclude_from_pos_files exclude_from_bom dnp)
		(fp_rect
			(start -0.925 0.47)
			(end 0.925 -0.47)
			(stroke
				(width 0.05)
				(type default)
			)
			(fill no)
			(layer "B.CrtYd")
		)
		(fp_line
			(start -0.494 -0.248)
			(end -0.494 0.25)
			(stroke
				(width 0.15)
				(type solid)
			)
			(layer "B.Fab")
		)
		(fp_line
			(start -0.494 0.25)
			(end 0.504 0.25)
			(stroke
				(width 0.15)
				(type solid)
			)
			(layer "B.Fab")
		)
		(fp_line
			(start 0.504 -0.248)
			(end -0.494 -0.248)
			(stroke
				(width 0.15)
				(type solid)
			)
			(layer "B.Fab")
		)
		(fp_line
			(start 0.504 0.25)
			(end 0.504 -0.248)
			(stroke
				(width 0.15)
				(type solid)
			)
			(layer "B.Fab")
		)
		(fp_text user "${REFERENCE}"
			(at -0.939 -4.599 0)
			(layer "B.Fab")
			(effects
				(font
					(size 0.7 0.7)
					(thickness 0.15)
				)
				(justify right top mirror)
			)
		)
		(fp_text user "License: Apache-2.0"
			(at -0.939 -5.799 0)
			(layer "B.Fab")
			(effects
				(font
					(size 0.7 0.7)
					(thickness 0.15)
				)
				(justify right top mirror)
			)
		)
		(fp_text user "Author: Antmicro"
			(at -0.939 -3.399 0)
			(layer "B.Fab")
			(effects
				(font
					(size 0.7 0.7)
					(thickness 0.15)
				)
				(justify right top mirror)
			)
		)
		(pad "1" smd roundrect
			(at -0.48 0)
			(size 0.59 0.64)
			(layers "B.Cu" "B.Mask" "B.Paste")
			(roundrect_rratio 0.25)
			(net 1 "GND")
			(pintype "passive")
		)
		(pad "2" smd roundrect
			(at 0.48 0)
			(size 0.59 0.64)
			(layers "B.Cu" "B.Mask" "B.Paste")
			(roundrect_rratio 0.25)
			(net 13 "VCC")
			(pintype "passive")
		)
	)
)
